# T6G (Grand Teton) — schematic netlist excerpt (pin names and nets, part order shuffled) for the footprints in the layout excerpt that follows; sources: Cadence DE-HDL packaged netlist, KiCad conversion of 04192023_DAF0TMB3IC0_F0TG_MB_C_brd_V02_OCP.brd

R3628  Q_RES  4.7K 1% EMPTY  pkg 0402LF  page 236 : A = P3V3_AUX ; B = INA230_1_A1
R2923  Q_RES  4.7K 5% EMPTY  pkg 0402LF  page 245 : A = P3V3_AUX ; B = PU_U181_INT

(kicad_pcb
	(version 20260206)
	(generator "pcbnew")
	(generator_version "10.0")
	(general
		(thickness 1.6)
		(legacy_teardrops no)
	)
	(paper "A4")
	(title_block
		(title "04192023_DAF0TMB3IC0_F0TG_MB_C_brd_V02_OCP.brd")
		(comment 1 "Grand Teton / footprints 1660-1661 of 8354")
	)
	(layers
		(0 "F.Cu" signal "TOP")
		(4 "In1.Cu" signal "GND")
		(6 "In2.Cu" signal "IN1")
		(8 "In3.Cu" signal "GND1")
		(10 "In4.Cu" signal "IN2")
		(12 "In5.Cu" signal "GND2")
		(14 "In6.Cu" signal "IN3")
		(16 "In7.Cu" signal "GND3")
		(18 "In8.Cu" signal "VCC")
		(20 "In9.Cu" signal "VCC1")
		(22 "In10.Cu" signal "GND4")
		(24 "In11.Cu" signal "IN4")
		(26 "In12.Cu" signal "GND5")
		(28 "In13.Cu" signal "IN5")
		(30 "In14.Cu" signal "GND6")
		(32 "In15.Cu" signal "IN6")
		(34 "In16.Cu" signal "GND7")
		(2 "B.Cu" signal "BOTTOM")
		(9 "F.Adhes" user "F.Adhesive")
		(11 "B.Adhes" user "B.Adhesive")
		(13 "F.Paste" user "Package Geometry/Pastemask Top")
		(15 "B.Paste" user "Package Geometry/Pastemask Bottom")
		(5 "F.SilkS" user "Ref Des/Silkscreen Top")
		(7 "B.SilkS" user "Ref Des/Silkscreen Bottom")
		(1 "F.Mask" user "Board Geometry/Soldermask Top")
		(3 "B.Mask" user "Board Geometry/Soldermask Bottom")
		(17 "Dwgs.User" user "User.Drawings")
		(19 "Cmts.User" user "User.Comments")
		(21 "Eco1.User" user "User.Eco1")
		(23 "Eco2.User" user "User.Eco2")
		(25 "Edge.Cuts" user "Board Geometry/Outline")
		(27 "Margin" user)
		(31 "F.CrtYd" user "Package Geometry/Place Bound Top")
		(29 "B.CrtYd" user "Package Geometry/Place Bound Bottom")
		(35 "F.Fab" user "Ref Des/Assembly Top")
		(33 "B.Fab" user "Ref Des/Assembly Bottom")
	)
	(footprint ""
		(layer "F.Cu")
		(at 445.157098 -92.468192 180)
		(property "Reference" "R3628"
			(at 0 0 180)
			(layer "F.SilkS")
			(hide yes)
			(effects
				(font
					(size 1.27 1.27)
				)
			)
		)
		(property "Value" ""
			(at 0 0 180)
			(layer "F.Fab")
			(effects
				(font
					(size 1.27 1.27)
				)
			)
		)
		(duplicate_pad_numbers_are_jumpers no)
		(fp_line
			(start 0.7874 0.4064)
			(end -0.7874 0.4064)
			(stroke
				(width 0.1524)
				(type default)
			)
			(layer "F.SilkS")
		)
		(fp_line
			(start 0.7874 -0.4064)
			(end 0.7874 0.4064)
			(stroke
				(width 0.1524)
				(type default)
			)
			(layer "F.SilkS")
		)
		(fp_line
			(start -0.7874 0.4064)
			(end -0.7874 -0.4064)
			(stroke
				(width 0.1524)
				(type default)
			)
			(layer "F.SilkS")
		)
		(fp_line
			(start -0.7874 -0.4064)
			(end 0.7874 -0.4064)
			(stroke
				(width 0.1524)
				(type default)
			)
			(layer "F.SilkS")
		)
		(fp_line
			(start 0.67945 0.3048)
			(end 0.120396 0.3048)
			(stroke
				(width 0.1)
				(type default)
			)
			(layer "F.Fab")
		)
		(fp_line
			(start 0.67945 -0.3048)
			(end 0.67945 0.3048)
			(stroke
				(width 0.1)
				(type default)
			)
			(layer "F.Fab")
		)
		(fp_line
			(start 0.12065 -0.2794)
			(end 0.12065 -0.3048)
			(stroke
				(width 0.1)
				(type default)
			)
			(layer "F.Fab")
		)
		(fp_line
			(start 0.12065 -0.3048)
			(end 0.67945 -0.3048)
			(stroke
				(width 0.1)
				(type default)
			)
			(layer "F.Fab")
		)
		(fp_line
			(start 0.120396 0.3048)
			(end 0.120396 0.2794)
			(stroke
				(width 0.1)
				(type default)
			)
			(layer "F.Fab")
		)
		(fp_line
			(start 0.120396 0.2794)
			(end -0.12065 0.2794)
			(stroke
				(width 0.1)
				(type default)
			)
			(layer "F.Fab")
		)
		(fp_line
			(start -0.12065 0.3048)
			(end -0.67945 0.3048)
			(stroke
				(width 0.1)
				(type default)
			)
			(layer "F.Fab")
		)
		(fp_line
			(start -0.12065 0.2794)
			(end -0.12065 0.3048)
			(stroke
				(width 0.1)
				(type default)
			)
			(layer "F.Fab")
		)
		(fp_line
			(start -0.12065 -0.2794)
			(end 0.12065 -0.2794)
			(stroke
				(width 0.1)
				(type default)
			)
			(layer "F.Fab")
		)
		(fp_line
			(start -0.12065 -0.305054)
			(end -0.12065 -0.2794)
			(stroke
				(width 0.1)
				(type default)
			)
			(layer "F.Fab")
		)
		(fp_line
			(start -0.67945 0.3048)
			(end -0.67945 -0.305054)
			(stroke
				(width 0.1)
				(type default)
			)
			(layer "F.Fab")
		)
		(fp_line
			(start -0.67945 -0.305054)
			(end -0.12065 -0.305054)
			(stroke
				(width 0.1)
				(type default)
			)
			(layer "F.Fab")
		)
		(pad "1" smd circle
			(at -0.40005 0 180)
			(size 0 0)
			(layers "F.Cu" "F.Mask" "F.Paste")
			(net "P3V3_AUX")
		)
		(pad "2" smd circle
			(at 0.40005 0 180)
			(size 0 0)
			(layers "F.Cu" "F.Mask" "F.Paste")
			(net "INA230_1_A1")
		)
	)
	(footprint ""
		(layer "F.Cu")
		(at 176.79162 -413.836358 90)
		(property "Reference" "R2923"
			(at 0 0 90)
			(layer "F.SilkS")
			(hide yes)
			(effects
				(font
					(size 1.27 1.27)
				)
			)
		)
		(property "Value" ""
			(at 0 0 90)
			(layer "F.Fab")
			(effects
				(font
					(size 1.27 1.27)
				)
			)
		)
		(duplicate_pad_numbers_are_jumpers no)
		(fp_line
			(start 0.7874 -0.4064)
			(end 0.7874 0.4064)
			(stroke
				(width 0.1524)
				(type default)
			)
			(layer "F.SilkS")
		)
		(fp_line
			(start -0.7874 -0.4064)
			(end 0.7874 -0.4064)
			(stroke
				(width 0.1524)
				(type default)
			)
			(layer "F.SilkS")
		)
		(fp_line
			(start 0.7874 0.4064)
			(end -0.7874 0.4064)
			(stroke
				(width 0.1524)
				(type default)
			)
			(layer "F.SilkS")
		)
		(fp_line
			(start -0.7874 0.4064)
			(end -0.7874 -0.4064)
			(stroke
				(width 0.1524)
				(type default)
			)
			(layer "F.SilkS")
		)
		(fp_line
			(start -0.12065 -0.305054)
			(end -0.12065 -0.2794)
			(stroke
				(width 0.1)
				(type default)
			)
			(layer "F.Fab")
		)
		(fp_line
			(start -0.67945 -0.305054)
			(end -0.12065 -0.305054)
			(stroke
				(width 0.1)
				(type default)
			)
			(layer "F.Fab")
		)
		(fp_line
			(start 0.67945 -0.3048)
			(end 0.67945 0.3048)
			(stroke
				(width 0.1)
				(type default)
			)
			(layer "F.Fab")
		)
		(fp_line
			(start 0.12065 -0.3048)
			(end 0.67945 -0.3048)
			(stroke
				(width 0.1)
				(type default)
			)
			(layer "F.Fab")
		)
		(fp_line
			(start 0.12065 -0.2794)
			(end 0.12065 -0.3048)
			(stroke
				(width 0.1)
				(type default)
			)
			(layer "F.Fab")
		)
		(fp_line
			(start -0.12065 -0.2794)
			(end 0.12065 -0.2794)
			(stroke
				(width 0.1)
				(type default)
			)
			(layer "F.Fab")
		)
		(fp_line
			(start 0.120396 0.2794)
			(end -0.12065 0.2794)
			(stroke
				(width 0.1)
				(type default)
			)
			(layer "F.Fab")
		)
		(fp_line
			(start -0.12065 0.2794)
			(end -0.12065 0.3048)
			(stroke
				(width 0.1)
				(type default)
			)
			(layer "F.Fab")
		)
		(fp_line
			(start 0.67945 0.3048)
			(end 0.120396 0.3048)
			(stroke
				(width 0.1)
				(type default)
			)
			(layer "F.Fab")
		)
		(fp_line
			(start 0.120396 0.3048)
			(end 0.120396 0.2794)
			(stroke
				(width 0.1)
				(type default)
			)
			(layer "F.Fab")
		)
		(fp_line
			(start -0.12065 0.3048)
			(end -0.67945 0.3048)
			(stroke
				(width 0.1)
				(type default)
			)
			(layer "F.Fab")
		)
		(fp_line
			(start -0.67945 0.3048)
			(end -0.67945 -0.305054)
			(stroke
				(width 0.1)
				(type default)
			)
			(layer "F.Fab")
		)
		(pad "1" smd circle
			(at -0.40005 0 90)
			(size 0 0)
			(layers "F.Cu" "F.Mask" "F.Paste")
			(net "P3V3_AUX")
		)
		(pad "2" smd circle
			(at 0.40005 0 90)
			(size 0 0)
			(layers "F.Cu" "F.Mask" "F.Paste")
			(net "PU_U181_INT")
		)
	)
)
